# TIMECARD (Time Appliance Project (Time Card)) — schematic parts with pin connectivity, parts 577–730 of 1119; source: Cadence DE-HDL packaged netlist (pstxprt.dat, pstxnet.dat, pstchip.dat)

R165  RESISTOR  10KOHM 1%  pkg SMC_0402R_H016  page 30 : 1 = XP1R2V_EN_R ; 2 = SG
R166  RESISTOR  1.13KOHM 1%  pkg SMC_0402R  page 30 : 1 = XP1R8V_VIN ; 2 = XP1R8V_EN_R
R167  RESISTOR  10KOHM 1%  pkg SMC_0402R_H016  page 9 : 1 = XP3R3V_FPGA ; 2 = FPGA_IN_RST_DLY_N
R168  RESISTOR  1MOHM 1%  pkg SMC_0402R_H016  page 20 : 1 = UNNAMED_9_CAPACITOR_I17_1 ; 2 = UNNAMED_9_BNO080LGA28_I29_XOUT3
R169  RESISTOR  330OHM 1%  pkg SMC_0402R_H016  page 26 : 1 = UNNAMED_14_OPTICAL_I289_A ; 2 = XP3R3V_FT4232
R170  RESISTOR  10KOHM 1%  pkg SMC_0402R_H016  page 25 : 1 = XP3R3V_FPGA ; 2 = FPGA_IO_0
R171  RESISTOR  4.7KOHM 1%  pkg SMC_0402R_H016  page 25 : 1 = SG ; 2 = FPGA_IO_0
R172  RESISTOR  10KOHM 1%  pkg SMC_0402R_H016  page 25 : 1 = XP3R3V_FPGA ; 2 = FPGA_IO_1
R173  RESISTOR  4.7KOHM 1%  pkg SMC_0402R_H016  page 25 : 1 = SG ; 2 = FPGA_IO_1
R174  RESISTOR  10KOHM 1%  pkg SMC_0402R_H016  page 30 : 1 = XP1R8V_EN_R ; 2 = SG
R175  RESISTOR  33OHM 1%  pkg SMC_0402R_H016  page 16 : 1 = PCIE_SMDAT ; 2 = EEPROM_SDA
R176  RESISTOR  33OHM 1%  pkg SMC_0402R_H016  page 16 : 1 = PCIE_SMCLK ; 2 = EEPROM_SCL
R177  RESISTOR  1.13KOHM 1%  pkg SMC_0402R  page 30 : 1 = XP1R2V_VIN ; 2 = XP1R2V_EN_R
R178  RESISTOR  4.7KOHM 1%  pkg SMC_0402R_H016  page 30 : 1 = XP3R3V ; 2 = XP1R2V_PG_R
R179  RESISTOR  4.7KOHM 1%  pkg SMC_0402R_H016  page 30 : 1 = XP3R3V ; 2 = XP1R8V_PG_R
R180  RESISTOR  1KOHM 1%  pkg SMC_0402R_H016  page 26 : 1 = UNNAMED_14_OPTICAL_I142_A ; 2 = XP5R0V
R181  RESISTOR  0OHM -  pkg SMC_0402R_H016  page 30 : 1 = XP1R2V_PG_R ; 2 = XP1R2V_FPGA_PG
R182  RESISTOR  0OHM -  pkg SMC_0402R_H016  page 30 : 1 = XP1R8V_PG_R ; 2 = XP1R8V_FPGA_PG
R183  RESISTOR  33OHM 1%  pkg SMC_0402R_H016  page 16 : 1 = EEPROM_I2C_SDA ; 2 = EEPROM_SDA
R184  RESISTOR  33OHM 1%  pkg SMC_0402R_H016  page 16 : 1 = EEPROM_I2C_SCL ; 2 = EEPROM_SCL
R185  RESISTOR  4.22KOHM 1%  pkg SMC_0402R  page 30 : 1 = XP1R2V_FPGA ; 2 = XP1R2V_FB
R186  RESISTOR  3KOHM 1%  pkg SMC_0402R_H016  page 30 : 1 = SG ; 2 = XP1R2V_FB
R187  RESISTOR  4.22KOHM 1%  pkg SMC_0402R  page 30 : 1 = XP1R8V_FPGA ; 2 = XP1R8V_FB
R188  RESISTOR  3.24KOHM 1%  pkg SMC_0402R_H014  page 30 : 1 = SG ; 2 = XP1R8V_FB
R189  RESISTOR  3.24KOHM 1%  pkg SMC_0402R_H014  page 30 : 1 = SG ; 2 = XP1R2V_FB
R190  RESISTOR  3.24KOHM 1%  pkg SMC_0402R_H014  page 30 : 1 = SG ; 2 = XP1R8V_FB
R191  RESISTOR  4.7KOHM 1%  pkg SMC_0402R_H016  page 10 : 1 = XP3R3V_FPGA ; 2 = FLASH_CS_N
R192  RESISTOR  4.7KOHM 1%  pkg SMC_0402R_H016  page 10 : 1 = FLASH_CLK ; 2 = SG
R193  RESISTOR  4.7KOHM 1%  pkg SMC_0402R_H016  page 10 : 1 = XP3R3V_FPGA ; 2 = FPGA_PROGRAM_N
R194  RESISTOR  4.7KOHM 1%  pkg SMC_0402R_H016  page 10 : 1 = XP3R3V_FPGA ; 2 = CFGBVS
R195  RESISTOR  33OHM 1%  pkg SMC_0402R_H016  page 10 : 1 = FPGA_TDO ; 2 = R_FPGA_TDO
R196  RESISTOR  100OHM 1%  pkg SMC_0402R_H016  page 10 : 1 = FPGA_MGTAVTT ; 2 = FPGA_MGTRREF
R197  RESISTOR  100OHM 1%  pkg SMC_0402R_H016  page 10 : 1 = MHZ125CLKP_CLKIN ; 2 = MHZ125CLKN_CLKIN
R198  RESISTOR  100OHM 1%  pkg SMC_0402R_H016  page 10 : 1 = PCIE_REFCLKP ; 2 = PCIE_REFCLKN
R199  RESISTOR  4.7KOHM 1%  pkg SMC_0402R_H016  page 10 : 1 = UNNAMED_127_MT25QL128ABA1ESESOP ; 2 = XP3R3V_FPGA
R200  RESISTOR  4.7KOHM 1%  pkg SMC_0402R_H016  page 10 : 1 = UNNAMED_127_MT25QL128ABA1ESES_1 ; 2 = XP3R3V_FPGA
R201  RESISTOR  4.7KOHM 1%  pkg SMC_0402R_H016  page 10 : 1 = UNNAMED_127_MT25QL128ABA1ESES_3 ; 2 = XP3R3V_FPGA
R202  RESISTOR  4.7KOHM 1%  pkg SMC_0402R_H016  page 10 : 1 = UNNAMED_127_MT25QL128ABA1ESES_2 ; 2 = XP3R3V_FPGA
R203  RESISTOR  33OHM 1%  pkg SMC_0402R_H016  page 10 : 1 = UNNAMED_127_MT25QL128ABA1ESESOP ; 2 = FLASH_DQ0_MOSI
R204  RESISTOR  33OHM 1%  pkg SMC_0402R_H016  page 10 : 1 = UNNAMED_127_MT25QL128ABA1ESES_1 ; 2 = FLASH_DQ1_MISO
R205  RESISTOR  33OHM 1%  pkg SMC_0402R_H016  page 10 : 1 = UNNAMED_127_MT25QL128ABA1ESES_3 ; 2 = FLASH_DQ2
R206  RESISTOR  33OHM 1%  pkg SMC_0402R_H016  page 10 : 1 = UNNAMED_127_MT25QL128ABA1ESES_2 ; 2 = FLASH_DQ3
R207  RESISTOR  0OHM -  pkg SMC_0402R_H016  page 10 : 1 = CCLK_0 ; 2 = FPGA_FLASH_CLK
R208  RESISTOR  330OHM 1%  pkg SMC_0402R_H016  page 26 : 1 = UNNAMED_14_OPTICAL_I292_A ; 2 = FPGA_DONE
R209  RESISTOR  4.7KOHM 1%  pkg SMC_0402R_H016  page 10 : 1 = FPGA_CFG_INIT_N ; 2 = XP3R3V_FPGA
R210  RESISTOR  330OHM 1%  pkg SMC_0402R_H016  page 10 : 1 = FPGA_DONE ; 2 = XP3R3V_FPGA
R211  RESISTOR  100OHM 1%  pkg SMC_0402R_H016  page 10 : 1 = XP3R3V_FPGA ; 2 = FPGA_M0
R212  RESISTOR  100OHM 1%  pkg SMC_0402R_H016  page 10 : 1 = FPGA_M0 ; 2 = SG
R213  RESISTOR  10KOHM 1%  pkg SMC_0402R_H016  page 10 : 1 = XP3R3V_FPGA ; 2 = FPGA_BRD_REV2
R214  RESISTOR  1KOHM 1%  pkg SMC_0402R_H016  page 10 : 1 = FPGA_BRD_REV2 ; 2 = SG
R215  RESISTOR  10KOHM 1%  pkg SMC_0402R_H016  page 10 : 1 = XP3R3V_FPGA ; 2 = FPGA_BRD_REV1
R216  RESISTOR  1KOHM 1%  pkg SMC_0402R_H016  page 10 : 1 = FPGA_BRD_REV1 ; 2 = SG
R217  RESISTOR  100OHM 1%  pkg SMC_0402R_H016  page 10 : 1 = XP3R3V_FPGA ; 2 = FPGA_M1
R218  RESISTOR  100OHM 1%  pkg SMC_0402R_H016  page 10 : 1 = FPGA_M1 ; 2 = SG
R219  RESISTOR  10KOHM 1%  pkg SMC_0402R_H016  page 10 : 1 = XP3R3V_FPGA ; 2 = FPGA_BRD_REV0
R220  RESISTOR  1KOHM 1%  pkg SMC_0402R_H016  page 10 : 1 = FPGA_BRD_REV0 ; 2 = SG
R221  RESISTOR  100OHM 1%  pkg SMC_0402R_H016  page 10 : 1 = XP3R3V_FPGA ; 2 = FPGA_M2
R222  RESISTOR  100OHM 1%  pkg SMC_0402R_H016  page 10 : 1 = FPGA_M2 ; 2 = SG
R223  RESISTOR  1KOHM 1%  pkg SMC_0402R_H016  page 11 : 1 = PUDC ; 2 = XP3R3V_FPGA
R224  RESISTOR  1KOHM 1%  pkg SMC_0402R_H016  page 11 : 1 = SG ; 2 = PUDC
R225  RESISTOR  330OHM 1%  pkg SMC_0402R_H016  page 31 : 1 = XP1R8V_FPGA_PG ; 2 = UNNAMED_515_CAPACITOR_I128_1
R226  RESISTOR  330OHM 1%  pkg SMC_0402R_H016  page 31 : 1 = XP1R8V_FPGA_PG ; 2 = XP3R3V_FPGA_EN_R
R227  RESISTOR  10KOHM 1%  pkg SMC_0402R_H016  page 31 : 1 = UNNAMED_515_CAPACITOR_I128_1 ; 2 = SG
R228  RESISTOR  1.13KOHM 1%  pkg SMC_0402R  page 31 : 1 = UNNAMED_515_CAPACITOR_I130_1 ; 2 = UNNAMED_515_CAPACITOR_I128_1
R229  RESISTOR  4.7KOHM 1%  pkg SMC_0402R_H016  page 31 : 1 = XP3R3V_FPGA ; 2 = UNNAMED_515_CAPACITOR_I138_1
R230  RESISTOR  0OHM -  pkg SMC_0402R_H016  page 31 : 1 = UNNAMED_515_CAPACITOR_I138_1 ; 2 = FPGA_CFG_INIT_N
R231  RESISTOR  4.22KOHM 1%  pkg SMC_0402R  page 31 : 1 = XP2R5V_FPGA ; 2 = UNNAMED_515_ISL80101IRAJZDFN10_
R232  RESISTOR  2.1KOHM 1%  pkg SMC_0402R  page 31 : 1 = SG ; 2 = UNNAMED_515_ISL80101IRAJZDFN10_
R233  RESISTOR  2.1KOHM 1%  pkg SMC_0402R  page 31 : 1 = SG ; 2 = UNNAMED_515_ISL80101IRAJZDFN10_
R234  RESISTOR  33OHM 1%  pkg SMC_0402R_H016  page 11 : 1 = FPGA_D00_MOSI ; 2 = FPGA_FLASH_DQ0_MOSI
R235  RESISTOR  4.7KOHM 1%  pkg SMC_0402R_H016  page 15 : 1 = VDD3V3_OSC_200M ; 2 = CLK_200M_OE
R236  RESISTOR  4.7KOHM 1%  pkg SMC_0402R_H016  page 15 : 1 = VDD3V3_OSC_125M ; 2 = CLK_125M_OE
R237  RESISTOR  10KOHM 1%  pkg SMC_0402R_H016  page 31 : 1 = XP3R3V_FPGA_EN_R ; 2 = SG
R238  RESISTOR  33OHM 1%  pkg SMC_0402R_H016  page 11 : 1 = FPGA_D01 ; 2 = FPGA_FLASH_DQ1_MISO
R239  RESISTOR  150OHM 1%  pkg SMC_0402R_H016  page 15 : 1 = OSC_200M_CLKN ; 2 = SG
R240  RESISTOR  150OHM 1%  pkg SMC_0402R_H016  page 15 : 1 = OSC_125M_CLKN ; 2 = SG
R241  RESISTOR  150OHM 1%  pkg SMC_0402R_H016  page 15 : 1 = OSC_200M_CLKP ; 2 = SG
R242  RESISTOR  150OHM 1%  pkg SMC_0402R_H016  page 15 : 1 = OSC_125M_CLKP ; 2 = SG
R243  RESISTOR  4.7KOHM 1%  pkg SMC_0402R_H016  page 29 : 1 = XP3R3V ; 2 = XP1R0V_PG
R244  RESISTOR  0OHM -  pkg SMC_0402R_H016  page 29 : 1 = XP3R3V_PG ; 2 = UNNAMED_523_CAPACITOR_I7_1
R245  RESISTOR  0OHM -  pkg SMC_0402R_H016  page 29 : 1 = XP1R0V_FPGA_PG ; 2 = XP1R0V_PG
R246  RESISTOR  5.1KOHM 1%  pkg SMC_0402R_H016  page 29 : 1 = UNNAMED_523_CAPACITOR_I7_1 ; 2 = SG
R247  RESISTOR  10KOHM 1%  pkg SMC_0402R_H016  page 29 : 1 = VIN_XP1R0V ; 2 = UNNAMED_523_CAPACITOR_I7_1
R248  RESISTOR  100KOHM 1%  pkg SMC_0402R_H016  page 29 : 1 = XP1R0V_RT ; 2 = XP1R0V_AGND
R249  RESISTOR  4.7KOHM 1%  pkg SMC_0402R_H016  page 29 : 1 = XP1R0V_COMP ; 2 = UNNAMED_523_CAPACITOR_I9_1
R250  RESISTOR  0OHM -  pkg SMC_0402R_H016  page 29 : 1 = XP1R0V_BT ; 2 = UNNAMED_523_CAPACITOR_I24_1
R251  RESISTOR  33.2KOHM 1%  pkg SMC_0402R_H016  page 29 : 1 = XP1R0V_AGND ; 2 = XP1R0V_FB_R_TO_AGND
R252  RESISTOR  0OHM -  pkg SMC_0603R_H024  page 29 : 1 = XP1R0V_AGND ; 2 = XP1R0V_FB_R_TO_AGND
R253  RESISTOR  2.2OHM 1%  pkg SMC_0805R_H026  page 29 : 1 = UNNAMED_523_CAPACITOR_I31_2 ; 2 = SG
R254  RESISTOR  20OHM 1%  pkg SMC_0402R_H016  page 29 : 1 = XP1R0V_FPGA ; 2 = UNNAMED_523_CAPACITOR_I28_1
R255  RESISTOR  22.6K 1%  pkg SMC_0402R_H016  page 29 : 1 = UNNAMED_523_CAPACITOR_I28_1 ; 2 = XP1R0V_FB_R_TO_AGND
R256  RESISTOR  1KOHM 1%  pkg SMC_0402R_H016  page 26 : 1 = UNNAMED_14_OPTICAL_I143_A ; 2 = UNNAMED_14_RESISTOR_I65_2
R257  RESISTOR  330OHM 1%  pkg SMC_0402R_H016  page 26 : 1 = UNNAMED_14_OPTICAL_I12_A ; 2 = XP3R3V_FPGA
R258  RESISTOR  330OHM 1%  pkg SMC_0402R_H016  page 26 : 1 = UNNAMED_14_OPTICAL_I11_A ; 2 = XP3R3V_FPGA
R259  RESISTOR  330OHM 1%  pkg SMC_0402R_H016  page 26 : 1 = UNNAMED_14_OPTICAL_I136_A ; 2 = XP3R3V_FPGA
R260  RESISTOR  1KOHM 1%  pkg SMC_0402R_H016  page 31 : 1 = XP3R3V ; 2 = XP3R3V_FPGA_EN_R
R261  RESISTOR  330OHM 1%  pkg SMC_0402R_H016  page 26 : 1 = UNNAMED_14_OPTICAL_I137_A ; 2 = XP3R3V_FPGA
R262  RESISTOR  1KOHM 1%  pkg SMC_0402R_H016  page 26 : 1 = UNNAMED_14_RESISTOR_I65_2 ; 2 = XP12R0V
R263  RESISTOR  0OHM -  pkg SMC_0402R_H016  page 28 : 1 = R_XP3R3V_PG ; 2 = XP3R3V_PG
R264  RESISTOR  100KOHM 1%  pkg SMC_0402R_H016  page 21 : 1 = XP3R3V_FPGA ; 2 = R_MAC_UART_RX_FPGA_TX
R265  RESISTOR  100KOHM 1%  pkg SMC_0402R_H016  page 21 : 1 = XP3R3V_FPGA ; 2 = UART_MAC_TX_FPGA_RX
R266  RESISTOR  33OHM 1%  pkg SMC_0402R_H016  page 21 : 1 = RSVD_DBG_USB_MUX_SEL ; 2 = XP5R0V_USB_CONN_DET
R267  RESISTOR  33OHM 1%  pkg SMC_0402R_H016  page 21 : 1 = UNNAMED_527_RESISTOR_I206_1 ; 2 = FPGA_IN_MAC_USB_OC_N
R268  RESISTOR  100KOHM 1%  pkg SMC_0402R_H016  page 22 : 1 = XP3R3V_FPGA ; 2 = GPS_UART_RXD
R269  RESISTOR  100KOHM 1%  pkg SMC_0402R_H016  page 22 : 1 = XP3R3V_FPGA ; 2 = UART_GPS_TX_FPGA_RX
R270  RESISTOR  4.7KOHM 1%  pkg SMC_0402R_H016  page 11 : 1 = SG ; 2 = FPGA_IN_GPSTP1_OUT
R271  RESISTOR  4.7KOHM 1%  pkg SMC_0402R_H016  page 11 : 1 = SG ; 2 = FPGA_IN_GPSTP2_OUT
R272  RESISTOR  100OHM 1%  pkg SMC_0402R_H016  page 26 : 1 = FPGA_OUT_SMA1_LED_RED_N ; 2 = UNNAMED_14_LED4PV14_I265_3
R273  RESISTOR  100OHM 1%  pkg SMC_0402R_H016  page 26 : 1 = FPGA_OUT_SMA2_LED_BLUE_N ; 2 = UNNAMED_14_LED4PV14_I266_1
R274  RESISTOR  100OHM 1%  pkg SMC_0402R_H016  page 26 : 1 = FPGA_OUT_SMA2_LED_GREEN_N ; 2 = UNNAMED_14_LED4PV14_I266_4
R275  RESISTOR  100OHM 1%  pkg SMC_0402R_H016  page 13 : 1 = FPGA_IN_MAC_PPS_OUTP ; 2 = FPGA_IN_MAC_PPS_OUTN
R276  RESISTOR  100OHM 1%  pkg SMC_0402R_H016  page 13 : 1 = FPGA_OUT_MAC_PPS_IN0P ; 2 = FPGA_OUT_MAC_PPS_IN0N
R277  RESISTOR  100OHM 1%  pkg SMC_0402R_H016  page 13 : 1 = FPGA_OUT_MAC_PPS_IN1P ; 2 = FPGA_OUT_MAC_PPS_IN1N
R278  RESISTOR  100OHM 1%  pkg SMC_0402R_H016  page 13 : 1 = MHZ200CLKP_CLKIN ; 2 = MHZ200CLKN_CLKIN
R279  RESISTOR  330OHM 1%  pkg SMC_0402R_H016  page 26 : 1 = UNNAMED_14_OPTICAL_I138_A ; 2 = XP3R3V_FPGA
R280  RESISTOR  330OHM 1%  pkg SMC_0402R_H016  page 26 : 1 = UNNAMED_14_OPTICAL_I139_A ; 2 = XP3R3V_FPGA
R281  RESISTOR  4.7KOHM 1%  pkg SMC_0402R_H016  page 19 : 1 = XP3R3V_FPGA ; 2 = ICP10100_I2C_SDA
R282  RESISTOR  4.7KOHM 1%  pkg SMC_0402R_H016  page 19 : 1 = XP3R3V_FPGA ; 2 = ICP10100_I2C_SCL
R283  RESISTOR  10KOHM 1%  pkg SMC_0402R_H016  page 25 : 1 = XP3R3V_FPGA ; 2 = FPGA_IO_2
R284  RESISTOR  4.7KOHM 1%  pkg SMC_0402R_H016  page 25 : 1 = SG ; 2 = FPGA_IO_2
R285  RESISTOR  10KOHM 1%  pkg SMC_0402R_H016  page 25 : 1 = XP3R3V_FPGA ; 2 = FPGA_IO_3
R286  RESISTOR  4.7KOHM 1%  pkg SMC_0402R_H016  page 25 : 1 = SG ; 2 = FPGA_IO_3
R287  RESISTOR  4.7KOHM 1%  pkg SMC_0402R_H016  page 21 : 1 = FPGA_IN_MAC_ALARM_OUT_N ; 2 = XP3R3V_FPGA
R288  RESISTOR  4.7KOHM 1%  pkg SMC_0402R_H016  page 11 : 1 = SG ; 2 = FPGA_IN_MAC_BITEOUT
R289  RESISTOR  4.7KOHM 1%  pkg SMC_0402R_H016  page 20 : 1 = XP3R3V_FPGA ; 2 = FPGA_IN_BNO080_INT_N
R290  RESISTOR  4.7KOHM 1%  pkg SMC_0402R_H016  page 20 : 1 = XP3R3V_FPGA ; 2 = BNO080_SA0
R291  RESISTOR  4.7KOHM 1%  pkg SMC_0402R_H016  page 20 : 1 = XP3R3V_FPGA ; 2 = R_BNO080_RST_N
R292  RESISTOR  10KOHM 1%  pkg SMC_0402R_H016  page 25 : 1 = XP3R3V_FPGA ; 2 = FPGA_IO_4
R293  RESISTOR  4.7KOHM 1%  pkg SMC_0402R_H016  page 25 : 1 = SG ; 2 = FPGA_IO_4
R294  RESISTOR  33OHM 1%  pkg SMC_0402R_H016  page 32 : 1 = XP5R0V_PG ; 2 = FPGA_CFG_INIT_N
R295  RESISTOR  10KOHM 1%  pkg SMC_0402R_H016  page 31 : 1 = XP3R3V_FPGA ; 2 = UNNAMED_515_NCP45560IMNTWGHDFN1
R296  RESISTOR  4.7KOHM 1%  pkg SMC_0402R_H016  page 18 : 1 = XP3R3V_FPGA ; 2 = R_SHT3X_RST_N
R297  RESISTOR  4.7KOHM 1%  pkg SMC_0402R_H016  page 18 : 1 = R_SHT3X_RST_N ; 2 = SG
R298  RESISTOR  33OHM 1%  pkg SMC_0402R_H016  page 18 : 1 = R_SHT3X_RST_N ; 2 = FPGA_OUT_SHT3X_RST_N
R299  RESISTOR  33OHM 1%  pkg SMC_0402R_H016  page 18 : 1 = R_SHT3X_ALERT_N ; 2 = FPGA_IN_SHT3X_ALERT_N
R300  RESISTOR  4.7KOHM 1%  pkg SMC_0402R_H016  page 18 : 1 = XP3R3V_FPGA ; 2 = FPGA_IN_SHT3X_ALERT_N
R301  RESISTOR  4.7KOHM 1%  pkg SMC_0402R_H016  page 20 : 1 = R_BNO080_RST_N ; 2 = SG
R302  RESISTOR  1KOHM 1%  pkg SMC_0402R_H016  page 20 : 1 = BNO080_SA0 ; 2 = SG
R303  RESISTOR  1KOHM 1%  pkg SMC_0402R_H016  page 20 : 1 = UNNAMED_9_BNO080LGA28_I29_PS1 ; 2 = SG
R304  RESISTOR  4.7KOHM 1%  pkg SMC_0402R_H016  page 20 : 1 = XP3R3V_FPGA ; 2 = R_BNO080_BOOT_N
R305  RESISTOR  1KOHM 1%  pkg SMC_0402R_H016  page 20 : 1 = UNNAMED_9_BNO080LGA28_I29_PS0 ; 2 = SG
R306  RESISTOR  4.7KOHM 1%  pkg SMC_0402R_H016  page 20 : 1 = XP3R3V_FPGA ; 2 = UNNAMED_9_BNO080LGA28_I29_CLKSE
R307  RESISTOR  1KOHM 1%  pkg SMC_0402R_H016  page 20 : 1 = UNNAMED_9_BNO080LGA28_I29_CLKSE ; 2 = SG
R308  RESISTOR  10KOHM 1%  pkg SMC_0402R_H016  page 25 : 1 = XP3R3V_FPGA ; 2 = FPGA_IO_5
R309  RESISTOR  4.7KOHM 1%  pkg SMC_0402R_H016  page 25 : 1 = SG ; 2 = FPGA_IO_5
R310  RESISTOR  0OHM -  pkg SMC_0402R_H016  page 16 : 1 = RGB_LED_I2C_SDA ; 2 = R_PCA9546_I2C_SDA
R311  RESISTOR  0OHM -  pkg SMC_0402R_H016  page 16 : 1 = RGB_LED_I2C_SCL ; 2 = R_PCA9546_I2C_SCL
R312  RESISTOR  0OHM -  pkg SMC_0402R_H016  page 16 : 1 = RGB_LED_I2C_SDA ; 2 = EEPROM_SDA
R313  RESISTOR  0OHM -  pkg SMC_0402R_H016  page 16 : 1 = RGB_LED_I2C_SCL ; 2 = EEPROM_SCL
R314  RESISTOR  4.7KOHM 1%  pkg SMC_0402R_H016  page 19 : 1 = XP3R3V_FPGA ; 2 = UNNAMED_8_PCA9508DPTSSOP8_I51_E
R315  RESISTOR  0OHM -  pkg SMC_0402R_H016  page 19 : 1 = ICP10100_I2C_SCL ; 2 = BF_ICP10100_I2C_SCL
R316  RESISTOR  0OHM -  pkg SMC_0402R_H016  page 19 : 1 = ICP10100_I2C_SDA ; 2 = BF_ICP10100_I2C_SDA
R317  RESISTOR  10KOHM 1%  pkg SMC_0402R_H016  page 26 : 1 = XP3R3V_FPGA ; 2 = R_RGB_LED_I2C_SDA
R318  RESISTOR  10KOHM 1%  pkg SMC_0402R_H016  page 26 : 1 = XP3R3V_FPGA ; 2 = R_RGB_LED_I2C_SCL
